# T6G (Grand Teton) — schematic netlist excerpt (pin names and nets, part order shuffled) for the footprints in the layout excerpt that follows; sources: Cadence DE-HDL packaged netlist, KiCad conversion of 04192023_DAF0TMB3IC0_F0TG_MB_C_brd_V02_OCP.brd

C1022  Q_CAP  100UF 4V 20% X6S  pkg C0805  page 312 : A = P0V9_CPU0_RT3_2A ; B = GND
PC313_5  Q_CAP  22UF 16V 20% X6S  pkg C0805  page 213 : A = SW_P12V_AUX_PVDDCR_CPU0_P1_FLT ; B = GND
C9003  Q_CAP  1UF 25V 10% EMPTY  pkg C0402  page 267 : A = U142_VS ; B = GND

(kicad_pcb
	(version 20260206)
	(generator "pcbnew")
	(generator_version "10.0")
	(general
		(thickness 1.6)
		(legacy_teardrops no)
	)
	(paper "A4")
	(title_block
		(title "04192023_DAF0TMB3IC0_F0TG_MB_C_brd_V02_OCP.brd")
		(comment 1 "Grand Teton / footprints 6641-6643 of 8354")
	)
	(layers
		(0 "F.Cu" signal "TOP")
		(4 "In1.Cu" signal "GND")
		(6 "In2.Cu" signal "IN1")
		(8 "In3.Cu" signal "GND1")
		(10 "In4.Cu" signal "IN2")
		(12 "In5.Cu" signal "GND2")
		(14 "In6.Cu" signal "IN3")
		(16 "In7.Cu" signal "GND3")
		(18 "In8.Cu" signal "VCC")
		(20 "In9.Cu" signal "VCC1")
		(22 "In10.Cu" signal "GND4")
		(24 "In11.Cu" signal "IN4")
		(26 "In12.Cu" signal "GND5")
		(28 "In13.Cu" signal "IN5")
		(30 "In14.Cu" signal "GND6")
		(32 "In15.Cu" signal "IN6")
		(34 "In16.Cu" signal "GND7")
		(2 "B.Cu" signal "BOTTOM")
		(9 "F.Adhes" user "F.Adhesive")
		(11 "B.Adhes" user "B.Adhesive")
		(13 "F.Paste" user "Package Geometry/Pastemask Top")
		(15 "B.Paste" user "Package Geometry/Pastemask Bottom")
		(5 "F.SilkS" user "Ref Des/Silkscreen Top")
		(7 "B.SilkS" user "Ref Des/Silkscreen Bottom")
		(1 "F.Mask" user "Board Geometry/Soldermask Top")
		(3 "B.Mask" user "Board Geometry/Soldermask Bottom")
		(17 "Dwgs.User" user "User.Drawings")
		(19 "Cmts.User" user "User.Comments")
		(21 "Eco1.User" user "User.Eco1")
		(23 "Eco2.User" user "User.Eco2")
		(25 "Edge.Cuts" user "Board Geometry/Outline")
		(27 "Margin" user)
		(31 "F.CrtYd" user "Package Geometry/Place Bound Top")
		(29 "B.CrtYd" user "Package Geometry/Place Bound Bottom")
		(35 "F.Fab" user "Ref Des/Assembly Top")
		(33 "B.Fab" user "Ref Des/Assembly Bottom")
	)
	(footprint ""
		(layer "B.Cu")
		(at 72.689974 -173.870112 90)
		(property "Reference" "PC313_5"
			(at 0 0 90)
			(layer "B.SilkS")
			(hide yes)
			(effects
				(font
					(size 1.27 1.27)
				)
				(justify mirror)
			)
		)
		(property "Value" ""
			(at 0 0 90)
			(layer "B.Fab")
			(effects
				(font
					(size 1.27 1.27)
				)
				(justify mirror)
			)
		)
		(duplicate_pad_numbers_are_jumpers no)
		(fp_line
			(start 1.524 -0.762)
			(end -1.524 -0.762)
			(stroke
				(width 0.1524)
				(type default)
			)
			(layer "B.SilkS")
		)
		(fp_line
			(start -1.524 -0.762)
			(end -1.524 0.762)
			(stroke
				(width 0.1524)
				(type default)
			)
			(layer "B.SilkS")
		)
		(fp_line
			(start 1.524 0.762)
			(end 1.524 -0.762)
			(stroke
				(width 0.1524)
				(type default)
			)
			(layer "B.SilkS")
		)
		(fp_line
			(start -1.524 0.762)
			(end 1.524 0.762)
			(stroke
				(width 0.1524)
				(type default)
			)
			(layer "B.SilkS")
		)
		(fp_line
			(start 1.1049 -0.724916)
			(end 1.1049 0.724916)
			(stroke
				(width 0.1)
				(type default)
			)
			(layer "B.Fab")
		)
		(fp_line
			(start -1.1049 -0.724916)
			(end 1.1049 -0.724916)
			(stroke
				(width 0.1)
				(type default)
			)
			(layer "B.Fab")
		)
		(fp_line
			(start 1.1049 0.724916)
			(end -1.1049 0.724916)
			(stroke
				(width 0.1)
				(type default)
			)
			(layer "B.Fab")
		)
		(fp_line
			(start -1.1049 0.724916)
			(end -1.1049 -0.724916)
			(stroke
				(width 0.1)
				(type default)
			)
			(layer "B.Fab")
		)
		(pad "1" smd rect
			(at 0.889 0 90)
			(size 1.016 1.27)
			(layers "B.Cu" "B.Mask" "B.Paste")
			(net "SW_P12V_AUX_PVDDCR_CPU0_P1_FLT")
		)
		(pad "2" smd rect
			(at -0.889 0 90)
			(size 1.016 1.27)
			(layers "B.Cu" "B.Mask" "B.Paste")
			(net "GND")
		)
	)
	(footprint ""
		(layer "B.Cu")
		(at 180.281834 -421.37711 90)
		(property "Reference" "C9003"
			(at 0 0 90)
			(layer "B.SilkS")
			(hide yes)
			(effects
				(font
					(size 1.27 1.27)
				)
				(justify mirror)
			)
		)
		(property "Value" ""
			(at 0 0 90)
			(layer "B.Fab")
			(effects
				(font
					(size 1.27 1.27)
				)
				(justify mirror)
			)
		)
		(duplicate_pad_numbers_are_jumpers no)
		(fp_line
			(start 0.7874 -0.4064)
			(end -0.7874 -0.4064)
			(stroke
				(width 0.1524)
				(type default)
			)
			(layer "B.SilkS")
		)
		(fp_line
			(start -0.7874 -0.4064)
			(end -0.7874 0.4064)
			(stroke
				(width 0.1524)
				(type default)
			)
			(layer "B.SilkS")
		)
		(fp_line
			(start 0.7874 0.4064)
			(end 0.7874 -0.4064)
			(stroke
				(width 0.1524)
				(type default)
			)
			(layer "B.SilkS")
		)
		(fp_line
			(start -0.7874 0.4064)
			(end 0.7874 0.4064)
			(stroke
				(width 0.1524)
				(type default)
			)
			(layer "B.SilkS")
		)
		(fp_line
			(start 0.67945 -0.305054)
			(end 0.12065 -0.305054)
			(stroke
				(width 0.1)
				(type default)
			)
			(layer "B.Fab")
		)
		(fp_line
			(start 0.12065 -0.305054)
			(end 0.12065 -0.2794)
			(stroke
				(width 0.1)
				(type default)
			)
			(layer "B.Fab")
		)
		(fp_line
			(start -0.12065 -0.3048)
			(end -0.67945 -0.3048)
			(stroke
				(width 0.1)
				(type default)
			)
			(layer "B.Fab")
		)
		(fp_line
			(start -0.67945 -0.3048)
			(end -0.67945 0.3048)
			(stroke
				(width 0.1)
				(type default)
			)
			(layer "B.Fab")
		)
		(fp_line
			(start 0.12065 -0.2794)
			(end -0.12065 -0.2794)
			(stroke
				(width 0.1)
				(type default)
			)
			(layer "B.Fab")
		)
		(fp_line
			(start -0.12065 -0.2794)
			(end -0.12065 -0.3048)
			(stroke
				(width 0.1)
				(type default)
			)
			(layer "B.Fab")
		)
		(fp_line
			(start 0.12065 0.2794)
			(end 0.12065 0.3048)
			(stroke
				(width 0.1)
				(type default)
			)
			(layer "B.Fab")
		)
		(fp_line
			(start -0.120396 0.2794)
			(end 0.12065 0.2794)
			(stroke
				(width 0.1)
				(type default)
			)
			(layer "B.Fab")
		)
		(fp_line
			(start 0.67945 0.3048)
			(end 0.67945 -0.305054)
			(stroke
				(width 0.1)
				(type default)
			)
			(layer "B.Fab")
		)
		(fp_line
			(start 0.12065 0.3048)
			(end 0.67945 0.3048)
			(stroke
				(width 0.1)
				(type default)
			)
			(layer "B.Fab")
		)
		(fp_line
			(start -0.120396 0.3048)
			(end -0.120396 0.2794)
			(stroke
				(width 0.1)
				(type default)
			)
			(layer "B.Fab")
		)
		(fp_line
			(start -0.67945 0.3048)
			(end -0.120396 0.3048)
			(stroke
				(width 0.1)
				(type default)
			)
			(layer "B.Fab")
		)
		(pad "1" smd circle
			(at 0.40005 0 270)
			(size 0 0)
			(layers "B.Cu" "B.Mask" "B.Paste")
			(net "U142_VS")
		)
		(pad "2" smd circle
			(at -0.40005 0 270)
			(size 0 0)
			(layers "B.Cu" "B.Mask" "B.Paste")
			(net "GND")
		)
	)
	(footprint ""
		(layer "B.Cu")
		(at 392.961622 -398.455134 180)
		(property "Reference" "C1022"
			(at 0 0 0)
			(layer "B.SilkS")
			(hide yes)
			(effects
				(font
					(size 1.27 1.27)
				)
				(justify mirror)
			)
		)
		(property "Value" ""
			(at 0 0 0)
			(layer "B.Fab")
			(effects
				(font
					(size 1.27 1.27)
				)
				(justify mirror)
			)
		)
		(duplicate_pad_numbers_are_jumpers no)
		(fp_line
			(start 1.524 0.762)
			(end 1.524 -0.762)
			(stroke
				(width 0.1524)
				(type default)
			)
			(layer "B.SilkS")
		)
		(fp_line
			(start 1.524 -0.762)
			(end -1.524 -0.762)
			(stroke
				(width 0.1524)
				(type default)
			)
			(layer "B.SilkS")
		)
		(fp_line
			(start -1.524 0.762)
			(end 1.524 0.762)
			(stroke
				(width 0.1524)
				(type default)
			)
			(layer "B.SilkS")
		)
		(fp_line
			(start -1.524 -0.762)
			(end -1.524 0.762)
			(stroke
				(width 0.1524)
				(type default)
			)
			(layer "B.SilkS")
		)
		(fp_line
			(start 1.1049 0.724916)
			(end -1.1049 0.724916)
			(stroke
				(width 0.1)
				(type default)
			)
			(layer "B.Fab")
		)
		(fp_line
			(start 1.1049 -0.724916)
			(end 1.1049 0.724916)
			(stroke
				(width 0.1)
				(type default)
			)
			(layer "B.Fab")
		)
		(fp_line
			(start -1.1049 0.724916)
			(end -1.1049 -0.724916)
			(stroke
				(width 0.1)
				(type default)
			)
			(layer "B.Fab")
		)
		(fp_line
			(start -1.1049 -0.724916)
			(end 1.1049 -0.724916)
			(stroke
				(width 0.1)
				(type default)
			)
			(layer "B.Fab")
		)
		(pad "1" smd rect
			(at 0.889 0 180)
			(size 1.016 1.27)
			(layers "B.Cu" "B.Mask" "B.Paste")
			(net "P0V9_CPU0_RT3_2A")
		)
		(pad "2" smd rect
			(at -0.889 0 180)
			(size 1.016 1.27)
			(layers "B.Cu" "B.Mask" "B.Paste")
			(net "GND")
		)
	)
)
